FILE_TYPE = MULTI_PHYS_TABLE;

PART 'Q_INDUCTOR4P_12'

{========================================================================================}
:VALUE              | CURRENT_AMP | PART_TYPE | MATERIAL | PART_NUMBER             = STANDARD        | LIFECYCLE      | PART_NUMBER             | JEDEC_TYPE                    | DESCRIPTION                                | MANUFTR | MANUF_PN             | RD_CMPLS_LVL | CMPLS_LVL    | CLASS      | DIP_SMD | FROM_PJ         | DATA                            | FP_ECN                  | EE_CHECK_LIST  | STATUS      | CREATOR | CREATEDAY  | PREFERENCE | PSL ;
{========================================================================================}
 '57A-6011A'        | '7A'        | 'THLF'    | 'IND'    | 'CV14470M000'(!)        = ''              | 'End of Life'  | 'CV14470M000'           |'L_57A-6011_EOL'| 'CHOCK 440UH.7A .+-20%(57A-6011A)'         | 'DTA'   | '57A-6011A'          | ''           | 'EP_Tmp'     | 'DISCRETE' | 'DIP'   | 'S80-PETER'     | '57A-6011A.pdf'                 | ''                      | ''             | ''          | ''      | '20120213' | ''         | '' 
 '57A-6011A'        | '7A'        | 'THLF'    | 'EMPTY'  | 'CV14470M000'(!)        = ''              | 'End of Life'  | 'CV14470M000'           |'L_57A-6011_EOL'| 'CHOCK 440UH.7A .+-20%(57A-6011A)'         | 'DTA'   | '57A-6011A'          | ''           | 'EP_Tmp'     | 'DISCRETE' | 'DIP'   | 'S80-PETER'     | '57A-6011A.pdf'                 | ''                      | ''             | ''          | ''      | '20120213' | ''         | '' 
 'PLW3216S900SQ2T1' | '370MA'     | 'SMLF'    | 'IND'    | 'CX0SQ2T1001'(!)        = ''              | 'End of Life'  | 'CX0SQ2T1001'           |'L_PLW3216S_EOL'| 'EMI FICTER PLW3216S900SQ2T1(63.370MA'     | 'MUR'   | 'PLW3216S900SQ2T1'   | ''           | 'EP'         | 'DISCRETE' | ''      | 'T14-KENNETH'   | 'PLW3216S.pdf'                  | ''                      | ''             | 'Preferred' | ''      | '20120213' | ''         | '' 
 'PLW3216S900SQ2T1' | '370MA'     | 'SMLF'    | 'EMPTY'  | 'CX0SQ2T1001'(!)        = ''              | 'End of Life'  | 'CX0SQ2T1001'           |'L_PLW3216S_EOL'| 'EMI FICTER PLW3216S900SQ2T1(63.370MA'     | 'MUR'   | 'PLW3216S900SQ2T1'   | ''           | 'EP'         | 'DISCRETE' | ''      | 'T14-KENNETH'   | 'PLW3216S.pdf'                  | ''                      | ''             | 'Preferred' | ''      | '20120213' | ''         | '' 
 '90/330MA'         | '330MA'     | 'SMLF'    | 'IND'    | 'CX1HN900000'(!)        = ''              | ''             | 'CX1HN900000'           |'L_DLW21HNXA'| 'EMI FILTER DLW21HN900SQ2L(90,330MA)'      | 'MUR'   | 'DLW21HN900SQ2L'     | 'EP(V1)'     | 'EP(V1)'     | 'DISCRETE' | ''      | 'T2L-CHEESE'    | 'MUR_DLW21HNXXXSQ2X.pdf'        | ''                      | ''             | ''          | ''      | '20120213' | ''         | '' 
 '90/330MA'         | '330MA'     | 'SMLF'    | 'EMPTY'  | 'CX1HN900000'(!)        = ''              | ''             | 'CX1HN900000'           |'L_DLW21HNXA'| 'EMI FILTER DLW21HN900SQ2L(90,330MA)'      | 'MUR'   | 'DLW21HN900SQ2L'     | 'EP(V1)'     | 'EP(V1)'     | 'DISCRETE' | ''      | 'T2L-CHEESE'    | 'MUR_DLW21HNXXXSQ2X.pdf'        | ''                      | ''             | ''          | ''      | '20120213' | ''         | '' 
 'MCI-3216-900'     | '370MA'     | 'SMLF'    | 'IND'    | 'CX216900000'(!)        = 'End of Design' | 'Comp-Approve' | 'CX216900000'           |'L_PLW3216S'| 'EMI FILTER MCI-3216-900(90,370MA)'        | 'MAG'   | 'MCI-3216-900'       | 'EP'         | 'EP(V1)'     | 'DISCRETE' | ''      | 'TU1D-MICHAEL'  | 'MCI-3216-900.pdf'              | ''                      | ''             | ''          | ''      | '20120213' | ''         | '' 
 'MCI-3216-900'     | '370MA'     | 'SMLF'    | 'EMPTY'  | 'CX216900000'(!)        = 'End of Design' | 'Comp-Approve' | 'CX216900000'           |'L_PLW3216S'| 'EMI FILTER MCI-3216-900(90,370MA)'        | 'MAG'   | 'MCI-3216-900'       | 'EP'         | 'EP(V1)'     | 'DISCRETE' | ''      | 'TU1D-MICHAEL'  | 'MCI-3216-900.pdf'              | ''                      | ''             | ''          | ''      | '20120213' | ''         | '' 
 'DLW21HN670SQ2L'   | '330MA'     | 'SMLF'    | 'IND'    | 'CX670SQ2005'(!)        = ''              | ''             | 'CX670SQ2005'           |'L_DLW21HN'| 'EMI FILTER DLW21HN670SQ2L (67.330MA)'     | 'MUR'   | 'DLW21HN670SQ2L'     | ''           | 'EP'         | 'DISCRETE' | ''      | 'J10-ICE'       | 'DLW21HNXXXSQ2X.pdf'            | ''                      | ''             | 'Preferred' | ''      | '20120213' | ''         | '' 
 'DLW21HN670SQ2L'   | '330MA'     | 'SMLF'    | 'EMPTY'  | 'CX670SQ2005'(!)        = ''              | ''             | 'CX670SQ2005'           |'L_DLW21HN'| 'EMI FILTER DLW21HN670SQ2L (67.330MA)'     | 'MUR'   | 'DLW21HN670SQ2L'     | ''           | 'EP'         | 'DISCRETE' | ''      | 'J10-ICE'       | 'DLW21HNXXXSQ2X.pdf'            | ''                      | ''             | 'Preferred' | ''      | '20120213' | ''         | '' 
 '90/400MA'         | '400MA'     | 'SMLF'    | 'IND'    | 'CX900T04014'(!)        = 'End of Design' | 'Comp-Approve' | 'CX900T04014'           |'L_WCM3216F2S'| 'FILTER WCM3216F2SF-900T04(90,400MA)'      | 'TTA'   | 'WCM3216F2SF-900T04' | 'EP'         | 'EP(V1)'     | 'DISCRETE' | ''      | 'S1W-JOSEPH'    | 'WCM3216F2SF-900T04.pdf'        | ''                      | ''             | ''          | ''      | '20120213' | ''         | '' 
 '90/400MA'         | '400MA'     | 'SMLF'    | 'EMPTY'  | 'CX900T04014'(!)        = 'End of Design' | 'Comp-Approve' | 'CX900T04014'           |'L_WCM3216F2S'| 'FILTER WCM3216F2SF-900T04(90,400MA)'      | 'TTA'   | 'WCM3216F2SF-900T04' | 'EP'         | 'EP(V1)'     | 'DISCRETE' | ''      | 'S1W-JOSEPH'    | 'WCM3216F2SF-900T04.pdf'        | ''                      | ''             | ''          | ''      | '20120213' | ''         | '' 
 'DLW31SN900SQ2L'   | '370MA'     | 'SMLF'    | 'IND'    | 'DC06304A009'(!)        = ''              | 'End of Life'  | 'DC06304A009'           |'L_PLW3216S_EOL'| 'CHOKE DLW31SN900SQ2L (63.370MA)'          | 'MUR'   | 'DLW31SN900SQ2L'     | ''           | 'EP'         | 'DISCRETE' | ''      | 'YK1-THOMAS'    | 'MUR_DLW31SNXXXSQXX.pdf'        | ''                      | ''             | 'Preferred' | ''      | '20120213' | ''         | '' 
 'DLW31SN900SQ2L'   | '370MA'     | 'SMLF'    | 'EMPTY'  | 'DC06304A009'(!)        = ''              | 'End of Life'  | 'DC06304A009'           |'L_PLW3216S_EOL'| 'CHOKE DLW31SN900SQ2L (63.370MA)'          | 'MUR'   | 'DLW31SN900SQ2L'     | ''           | 'EP'         | 'DISCRETE' | ''      | 'YK1-THOMAS'    | 'MUR_DLW31SNXXXSQXX.pdf'        | ''                      | ''             | 'Preferred' | ''      | '20120213' | ''         | '' 
 'DLW21SN900SQ2L'   | '330MA'     | 'SMLF'    | 'IND'    | 'DC09004A006'(!)        = 'Potential'     | 'End of Life'  | 'DC09004A006'           |'L_DLW21HNXA_EOL'| 'CHOKE DLW21SN900SQ2L(330MA.90)'           | 'MUR'   | 'DLW21SN900SQ2L'     | ''           | 'EP_Tmp'     | 'DISCRETE' | ''      | 'JN3-LUNG'      | 'DLW21SNXXXSQ2X.pdf'            | ''                      | ''             | ''          | ''      | '20120213' | ''         | '' 
 'DLW21SN900SQ2L'   | '330MA'     | 'SMLF'    | 'EMPTY'  | 'DC09004A006'(!)        = 'Potential'     | 'End of Life'  | 'DC09004A006'           |'L_DLW21HNXA_EOL'| 'CHOKE DLW21SN900SQ2L(330MA.90)'           | 'MUR'   | 'DLW21SN900SQ2L'     | ''           | 'EP_Tmp'     | 'DISCRETE' | ''      | 'JN3-LUNG'      | 'DLW21SNXXXSQ2X.pdf'            | ''                      | ''             | ''          | ''      | '20120213' | ''         | '' 
 '1.8MH'            | '6A'        | 'THLF'    | 'IND'    | 'DC21860T000'(!)        = ''              | ''             | 'DC21860T000'           |'L_WT1697'| 'CHOKE DIP 1.8MH +-35% 6A WT1697-182-B6.5' | 'MGT'   | 'WT1697-182-B6.5'    | ''           | 'EU(V1)_Tmp' | 'DISCRETE' | 'DIP'   | 'LB4E-NC'       | 'MGT_WT1697-182-B6-5.pdf'       | ''                      | 'L_WT1697.xls' | ''          | ''      | '20120213' | ''         | '' 
 '1.8MH'            | '6A'        | 'THLF'    | 'EMPTY'  | 'DC21860T000'(!)        = ''              | ''             | 'DC21860T000'           |'L_WT1697'| 'CHOKE DIP 1.8MH +-35% 6A WT1697-182-B6.5' | 'MGT'   | 'WT1697-182-B6.5'    | ''           | 'EU(V1)_Tmp' | 'DISCRETE' | 'DIP'   | 'LB4E-NC'       | 'MGT_WT1697-182-B6-5.pdf'       | ''                      | 'L_WT1697.xls' | ''          | ''      | '20120213' | ''         | '' 
 'DLW21SN900SQ2L'   | '330MA'     | 'SMLF'    | 'IND'    | 'SC09004T000'(!)        = ''              | 'End of Life'  | 'SC09004T000'           |'L_DLW21HNXA_EOL'| 'CHOKE DLW21SN900SQ2L(330MA.90)HUA CON'    | 'MUR'   | 'DLW21SN900SQ2L'     | ''           | 'EP'         | 'DISCRETE' | ''      | 'N2P-LUNG'      | 'DLW21SNXXXSQ2X.pdf'            | ''                      | ''             | ''          | ''      | '20120213' | ''         | '' 
 'DLW21SN900SQ2L'   | '330MA'     | 'SMLF'    | 'EMPTY'  | 'SC09004T000'(!)        = ''              | 'End of Life'  | 'SC09004T000'           |'L_DLW21HNXA_EOL'| 'CHOKE DLW21SN900SQ2L(330MA.90)HUA CON'    | 'MUR'   | 'DLW21SN900SQ2L'     | ''           | 'EP'         | 'DISCRETE' | ''      | 'N2P-LUNG'      | 'DLW21SNXXXSQ2X.pdf'            | ''                      | ''             | ''          | ''      | '20120213' | ''         | '' 
 'DLW21HN'          | '330MA'     | 'SMLF'    | 'IND'    | 'SC09004T001'(!)        = ''              | ''             | 'SC09004T001'           |'L_DLW21HN'| 'CHOKE SMD DLW21HN(330MA.90+-25%)EMS-QMX'  | 'MUR'   | 'DLW21HN900SQ2L'     | ''           | 'EP'         | 'DISCRETE' | ''      | 'E08-DANNY'     | 'MUR_DLW21HN-SERIES.pdf'        | ''                      | ''             | ''          | ''      | '20120213' | ''         | '' 
 'DLW21HN'          | '330MA'     | 'SMLF'    | 'EMPTY'  | 'SC09004T001'(!)        = ''              | ''             | 'SC09004T001'           |'L_DLW21HN'| 'CHOKE SMD DLW21HN(330MA.90+-25%)EMS-QMX'  | 'MUR'   | 'DLW21HN900SQ2L'     | ''           | 'EP'         | 'DISCRETE' | ''      | 'E08-DANNY'     | 'MUR_DLW21HN-SERIES.pdf'        | ''                      | ''             | ''          | ''      | '20120213' | ''         | '' 
 '67/320MA'         | '320MA'     | 'SMLF'    | 'IND'    | 'CX21SN67000'(!)        = ''              | ''             | 'CX21SN67000'           |'L_DLW21HNXA'| 'EMI FILTER DLW21SN670HQ2L(67,320MA)'      | 'MUR'   | 'DLW21SN670HQ2L'     | 'EU(V1)'     | ''           | 'DISCRETE' | ''      | 'T2A-TONY'      | 'MUR_DLW21S.pdf'                | ''                      | ''             | ''          | ''      | '20120604' | ''         | '' 
 '67/320MA'         | '320MA'     | 'SMLF'    | 'EMPTY'  | 'CX21SN67000'(!)        = ''              | ''             | 'CX21SN67000'           |'L_DLW21HNXA'| 'EMI FILTER DLW21SN670HQ2L(67,320MA)'      | 'MUR'   | 'DLW21SN670HQ2L'     | 'EU(V1)'     | ''           | 'DISCRETE' | ''      | 'T2A-TONY'      | 'MUR_DLW21S.pdf'                | ''                      | ''             | ''          | ''      | '20120604' | ''         | '' 
 'MCM2012D900FBE'   | '300MA'     | 'SMLF'    | 'IND'    | 'CX00D900000'(!)        = ''              | 'End of Life'  | 'CX00D900000'           |'L_MCM2012D_EOL'| 'EMI FILTER MCM2012D900FBE(90,300MA)'      | 'MUR'   | 'MCM2012D900FBE'     | 'EP(V1)'     | 'EP(V1)'     | 'DISCRETE' | ''      | 'TU1J-L-J'      | 'ITC_MCM2012D series_REVA0.pdf' | ''                      | ''             | ''          | ''      | '20130425' | ''         | '' 
 'MCM2012D900FBE'   | '300MA'     | 'SMLF'    | 'EMPTY'  | 'CX00D900000'(!)        = ''              | 'End of Life'  | 'CX00D900000'           |'L_MCM2012D_EOL'| 'EMI FILTER MCM2012D900FBE(90,300MA)'      | 'MUR'   | 'MCM2012D900FBE'     | 'EP(V1)'     | 'EP(V1)'     | 'DISCRETE' | ''      | 'TU1J-L-J'      | 'ITC_MCM2012D series_REVA0.pdf' | ''                      | ''             | ''          | ''      | '20130425' | ''         | '' 
 '500NH'            | '45A'       | 'SMLF'    | 'IND'    | 'CV+50^0KZ00'(!)        = ''              | ''             | 'CV+50^0KZ00'           |'L_2HCB158467-501'| 'IND SMD 500NH +-10% 45A(2HCB158467-501)'  | 'DTA'   | '2HCB158467-501'     | 'EP(V1)'     | ''           | 'DISCRETE' | ''      | 'T2R-AARON'     | 'DTA_2HCB158467-501.pdf'        | ''                      | ''             | ''          | ''      | '20140206' | ''         | '' 
 '500NH'            | '45A'       | 'SMLF'    | 'EMPTY'  | 'CV+50^0KZ00'(!)        = ''              | ''             | 'CV+50^0KZ00'           |'L_2HCB158467-501'| 'IND SMD 500NH +-10% 45A(2HCB158467-501)'  | 'DTA'   | '2HCB158467-501'     | 'EP(V1)'     | ''           | 'DISCRETE' | ''      | 'T2R-AARON'     | 'DTA_2HCB158467-501.pdf'        | ''                      | ''             | ''          | ''      | '20140206' | ''         | '' 
 'PI62-10-FPIZ'     | '40A'       | 'SMLF'    | 'IND'    | 'CV+50^0KZ02'(!)        = ''              | ''             | 'CV+50^0KZ02'           |'L_2HCB158467-501'| 'IND SMD 500NH +-10% 40A(PI62-10-FPIZ)'    | 'VCR'   | 'PI62-10-FPIZ'       | 'EU(V1)'     | ''           | 'DISCRETE' | ''      | 'T2H-HANCE'     | 'VCR_PI62-10-FPIZ_RevD.pdf'     | ''                      | ''             | ''          | ''      | '20140206' | ''         | '' 
 'PI62-10-FPIZ'     | '40A'       | 'SMLF'    | 'EMPTY'  | 'CV+50^0KZ02'(!)        = ''              | ''             | 'CV+50^0KZ02'           |'L_2HCB158467-501'| 'IND SMD 500NH +-10% 40A(PI62-10-FPIZ)'    | 'VCR'   | 'PI62-10-FPIZ'       | 'EU(V1)'     | ''           | 'DISCRETE' | ''      | 'T2H-HANCE'     | 'VCR_PI62-10-FPIZ_RevD.pdf'     | ''                      | ''             | ''          | ''      | '20140206' | ''         | '' 
 '500NH'            | '40A'       | 'SMLF'    | 'IND'    | 'CV+50^0KZ03'(!)        = ''              | ''             | 'CV+50^0KZ03'           |'L_CTX01-19089-R'| 'IND SMD 500NH +-10% 40A(CTX01-19089-R)'   | 'EAN'   | 'CTX01-19089-R'      | 'EP(V1)'     | ''           | 'DISCRETE' | ''      | 'T2R-AARON'     | 'EAN_CTX01-19089-R.pdf'         | ''                      | ''             | ''          | ''      | '20140527' | ''         | '' 
 '500NH'            | '40A'       | 'SMLF'    | 'EMPTY'  | 'CV+50^0KZ03'(!)        = ''              | ''             | 'CV+50^0KZ03'           |'L_CTX01-19089-R'| 'IND SMD 500NH +-10% 40A(CTX01-19089-R)'   | 'EAN'   | 'CTX01-19089-R'      | 'EP(V1)'     | ''           | 'DISCRETE' | ''      | 'T2R-AARON'     | 'EAN_CTX01-19089-R.pdf'         | ''                      | ''             | ''          | ''      | '20140527' | ''         | '' 
 'DLW21HN900HQ2L'   | '220MA'     | 'SMLF'    | 'IND'    | 'CX1HN900001'(!)        = ''              | ''             | 'CX1HN900001'           |'L_DLW21HN'| 'EMI FILTER DLW21HN900HQ2L(50V,220MA,90)'  | 'MUR'   | 'DLW21HN900HQ2L'     | 'EP(V1)'     | 'EP(V1)'     | 'DISCRETE' | ''      | 'T2H-CF'        | 'MUR_DLW21HN900HQ2L.pdf'        | ''                      | ''             | ''          | ''      | '20141225' | ''         | '' 
 'DLW21HN900HQ2L'   | '220MA'     | 'SMLF'    | 'EMPTY'  | 'CX1HN900001'(!)        = ''              | ''             | 'CX1HN900001'           |'L_DLW21HN'| 'EMI FILTER DLW21HN900HQ2L(50V,220MA,90)'  | 'MUR'   | 'DLW21HN900HQ2L'     | 'EP(V1)'     | 'EP(V1)'     | 'DISCRETE' | ''      | 'T2H-CF'        | 'MUR_DLW21HN900HQ2L.pdf'        | ''                      | ''             | ''          | ''      | '20141225' | ''         | '' 
 '500NH'            | '40A'       | 'SMLF'    | 'IND'    | 'CV+50^0KZ04'(!)        = ''              | ''             | 'CV+50^0KZ04'           |'L_FPV1507-500-R'| 'IND SMD 500NH 10% 40A(FPV1507-500-R)'     | 'BUS'   | 'FPV1507-500-R'      | 'EP(V1)'     | ''           | 'DISCRETE' | ''      | 'T2H-AARON'     | 'BUS_FPV1507-500-R.pdf'         | ''                      | ''             | ''          | ''      | '20150402' | ''         | '' 
 '500NH'            | '40A'       | 'SMLF'    | 'EMPTY'  | 'CV+50^0KZ04'(!)        = ''              | ''             | 'CV+50^0KZ04'           |'L_FPV1507-500-R'| 'IND SMD 500NH 10% 40A(FPV1507-500-R)'     | 'BUS'   | 'FPV1507-500-R'      | 'EP(V1)'     | ''           | 'DISCRETE' | ''      | 'T2H-AARON'     | 'BUS_FPV1507-500-R.pdf'         | ''                      | ''             | ''          | ''      | '20150402' | ''         | '' 
 'EXC24CH900U'      | '0.13A'     | 'SMLF'    | 'IND'    | 'CXCH900U000'(!)        = 'End of Design' | 'Comp-Approve' | 'CXCH900U000'           |'L_EXC24CH_1-25X1'| 'EMI FILTER EXC24CH900U(90,0.13A)'         | 'MAT'   | 'EXC24CH900U'        | 'EP(V1)'     | 'EP(V1)'     | 'DISCRETE' | ''      | 'T6U-KIMMY'     | 'MAT_EXC24CH900U.pdf'           | ''                      | ''             | ''          | ''      | '20170418' | ''         | '' 
 'EXC24CH900U'      | '0.13A'     | 'SMLF'    | 'EMPTY'  | 'CXCH900U000'(!)        = 'End of Design' | 'Comp-Approve' | 'CXCH900U000'           |'L_EXC24CH_1-25X1'| 'EMI FILTER EXC24CH900U(90,0.13A)'         | 'MAT'   | 'EXC24CH900U'        | 'EP(V1)'     | 'EP(V1)'     | 'DISCRETE' | ''      | 'T6U-KIMMY'     | 'MAT_EXC24CH900U.pdf'           | ''                      | ''             | ''          | ''      | '20170418' | ''         | '' 
 '375NH'            | '52A'       | 'SMLF'    | 'IND'    | 'CV+37^0TZ00'(!)        = ''              | ''             | 'CV+37^0TZ00'           |'L_CTX01-19603-R_14-6X8-3'| 'IND SMD 375NH +6/-5% 52A(CTX01-19603-R)'  | 'BUS'   | 'CTX01-19603-R'      | 'EP(V1)'     | ''           | 'DISCRETE' | ''      | 'T2H-HSUEH-YEN' | 'BUS_CTX01-19603-R.pdf'         | ''                      | ''             | ''          | ''      | '20170525' | ''         | '' 
 '375NH'            | '52A'       | 'SMLF'    | 'EMPTY'  | 'CV+37^0TZ00'(!)        = ''              | ''             | 'CV+37^0TZ00'           |'L_CTX01-19603-R_14-6X8-3'| 'IND SMD 375NH +6/-5% 52A(CTX01-19603-R)'  | 'BUS'   | 'CTX01-19603-R'      | 'EP(V1)'     | ''           | 'DISCRETE' | ''      | 'T2H-HSUEH-YEN' | 'BUS_CTX01-19603-R.pdf'         | ''                      | ''             | ''          | ''      | '20170525' | ''         | '' 
 'PLW3216S261SQ2T1' | '310MA'     | 'SMLF'    | 'IND'    | 'CX1SQ2T1003'(!)        = ''              | ''             | 'CX1SQ2T1003'           |'L_PLW3216S'| 'FILTER PLW3216S261SQ2T1(80,310MA)'        | 'MUR'   | 'PLW3216S261SQ2T1'   | ''           | ''           | 'DISCRETE' | ''      | 'T2N-FRANK'     | 'MUR_PLW3216S261SQ2T1.pdf'      | ''                      | ''             | ''          | ''      | '20180927' | ''         | '' 
 'PLW3216S261SQ2T1' | '310MA'     | 'SMLF'    | 'EMPTY'  | 'CX1SQ2T1003'(!)        = ''              | ''             | 'CX1SQ2T1003'           |'L_PLW3216S'| 'FILTER PLW3216S261SQ2T1(80,310MA)'        | 'MUR'   | 'PLW3216S261SQ2T1'   | ''           | ''           | 'DISCRETE' | ''      | 'T2N-FRANK'     | 'MUR_PLW3216S261SQ2T1.pdf'      | ''                      | ''             | ''          | ''      | '20180927' | ''         | '' 
 '470UH'            | '18A'       | 'SMLF'    | 'IND'    | 'TMP_JBP_CARLOS_0213_1'(!) = ''              | ''             | 'TMP_JBP_CARLOS_0213_1' |'L_PA5141_23X23'| 'IND SMD 470UH 40% 18A(PA5141.505NLT)'     | 'PLE'   | 'PA5141.505NLT'      | ''           | ''           | 'DISCRETE' | ''      | 'JBP-CARLOS'    | 'PLE_PA5141.505NLT.pdf'         | ''                      | ''             | ''          | ''      | '20190215' | ''         | '' 
 '470UH'            | '18A'       | 'SMLF'    | 'EMPTY'  | 'TMP_JBP_CARLOS_0213_1'(!) = ''              | ''             | 'TMP_JBP_CARLOS_0213_1' |'L_PA5141_23X23'| 'IND SMD 470UH 40% 18A(PA5141.505NLT)'     | 'PLE'   | 'PA5141.505NLT'      | ''           | ''           | 'DISCRETE' | ''      | 'JBP-CARLOS'    | 'PLE_PA5141.505NLT.pdf'         | ''                      | ''             | ''          | ''      | '20190215' | ''         | '' 
 '3.6UH'            | '33A'       | 'SMLF'    | 'IND'    | 'CV-36Y0TZ00'(!)        = ''              | ''             | 'CV-36Y0TZ00'           |'L_60933_24-5X26'| 'IND SMD 3.6UH +15/-25% 33A(60933)'        | 'PYP'   | '60933'              | ''           | ''           | 'DISCRETE' | ''      | 'T2N-CHEER'     | 'PYP_60933.pdf'                 | ''                      | ''             | ''          | ''      | '20190328' | ''         | '' 
 '3.6UH'            | '33A'       | 'SMLF'    | 'EMPTY'  | 'CV-36Y0TZ00'(!)        = ''              | ''             | 'CV-36Y0TZ00'           |'L_60933_24-5X26'| 'IND SMD 3.6UH +15/-25% 33A(60933)'        | 'PYP'   | '60933'              | ''           | ''           | 'DISCRETE' | ''      | 'T2N-CHEER'     | 'PYP_60933.pdf'                 | ''                      | ''             | ''          | ''      | '20190328' | ''         | '' 
 'DLP11TB800UL2L'   | '0.1A'      | 'SMLF'    | 'IND'    | 'CX800UL2000'(!)        = 'End of Design' | 'Comp-Approve' | 'CX800UL2000'           |'L_DLP11TB_1-25X1'| 'EMI FILTER DLP11TB800UL2L(80OHM,0.1A)'    | 'MUR'   | 'DLP11TB800UL2L'     | 'EP(V1)'     | 'EP(V1)'     | 'DISCRETE' | ''      | 'S3D-ALAN'      | 'MUR_DLP11TB800UL2L.pdf'        | 'DLP11TB800UL2L.msg'    | ''             | ''          | ''      | '20191115' | ''         | '' 
 'DLP11TB800UL2L'   | '0.1A'      | 'SMLF'    | 'EMPTY'  | 'CX800UL2000'(!)        = 'End of Design' | 'Comp-Approve' | 'CX800UL2000'           |'L_DLP11TB_1-25X1'| 'EMI FILTER DLP11TB800UL2L(80OHM,0.1A)'    | 'MUR'   | 'DLP11TB800UL2L'     | 'EP(V1)'     | 'EP(V1)'     | 'DISCRETE' | ''      | 'S3D-ALAN'      | 'MUR_DLP11TB800UL2L.pdf'        | 'DLP11TB800UL2L.msg'    | ''             | ''          | ''      | '20191115' | ''         | '' 
 'DLP0NSN900HL2L'   | '1A'        | 'SMLF'    | 'IND'    | 'CX900HL2001'(!)        = 'End of Design' | 'End of Life'  | 'CX900HL2001'           |'L_DLP0NSN_0-85X0-65_EOL'| 'EMI FILTER DLP0NSN900HL2L(90,0.1A)'       | 'MUR'   | 'DLP0NSN900HL2L'     | 'EP(V1)'     | 'EP(V1)'     | 'DISCRETE' | ''      | 'S3D-ALAN'      | 'MUR_DLP0NSN900HL2L.pdf'        | 'DLP0NSN900HL2L.msg'    | ''             | ''          | ''      | '20191119' | ''         | '' 
 'DLP0NSN900HL2L'   | '1A'        | 'SMLF'    | 'EMPTY'  | 'CX900HL2001'(!)        = 'End of Design' | 'End of Life'  | 'CX900HL2001'           |'L_DLP0NSN_0-85X0-65_EOL'| 'EMI FILTER DLP0NSN900HL2L(90,0.1A)'       | 'MUR'   | 'DLP0NSN900HL2L'     | 'EP(V1)'     | 'EP(V1)'     | 'DISCRETE' | ''      | 'S3D-ALAN'      | 'MUR_DLP0NSN900HL2L.pdf'        | 'DLP0NSN900HL2L.msg'    | ''             | ''          | ''      | '20191119' | ''         | '' 
 '105NH'            | '100A'      | 'SMLF'    | 'IND'    | 'CV+11^0TZ00'(!)        = ''              | ''             | 'CV+11^0TZ00'           |'L_DHCME1211Q-111QL_11-7X5-7'| 'IND SMD 105NH 15% 100A(DHCME1211Q-111QL)' | 'DTA'   | 'DHCME1211Q-111QL'   | 'EP(V1)'     | ''           | 'DISCRETE' | ''      | 'S8Z-FRANK'     | 'DTA_DHCME1211Q-111QL.pdf'      | 'DHCME1211Q-111QL.msg'  | ''             | ''          | ''      | '20200416' | ''         | '' 
 '105NH'            | '100A'      | 'SMLF'    | 'EMPTY'  | 'CV+11^0TZ00'(!)        = ''              | ''             | 'CV+11^0TZ00'           |'L_DHCME1211Q-111QL_11-7X5-7'| 'IND SMD 105NH 15% 100A(DHCME1211Q-111QL)' | 'DTA'   | 'DHCME1211Q-111QL'   | 'EP(V1)'     | ''           | 'DISCRETE' | ''      | 'S8Z-FRANK'     | 'DTA_DHCME1211Q-111QL.pdf'      | 'DHCME1211Q-111QL.msg'  | ''             | ''          | ''      | '20200416' | ''         | '' 
 '100UH'            | '1A'        | 'SMLF'    | 'IND'    | 'CV11010MZ00'(!)        = ''              | ''             | 'CV11010MZ00'           |'L_CTX01-19479-R_7-3X7-3'| 'IND SMD 100UH +-20% 1A(CTX01-19479-R)'    | 'BUS'   | 'CTX01-19479-R'      | 'EP(V1)'     | 'EP(V1)'     | 'DISCRETE' | ''      | 'T2M-CHRIS'     | 'BUS_CTX01-19479-R.pdf'         | ''                      | ''             | ''          | ''      | '20201221' | ''         | '' 
 '100UH'            | '1A'        | 'SMLF'    | 'EMPTY'  | 'CV11010MZ00'(!)        = ''              | ''             | 'CV11010MZ00'           |'L_CTX01-19479-R_7-3X7-3'| 'IND SMD 100UH +-20% 1A(CTX01-19479-R)'    | 'BUS'   | 'CTX01-19479-R'      | 'EP(V1)'     | 'EP(V1)'     | 'DISCRETE' | ''      | 'T2M-CHRIS'     | 'BUS_CTX01-19479-R.pdf'         | ''                      | ''             | ''          | ''      | '20201221' | ''         | '' 
 '650UH'            | '85A'       | 'THLF'    | 'IND'    | 'DC165^00000'(!)        = ''              | ''             | 'DC165^00000'           |'LC24-5_P20W10'| 'CHOKE 650UH 30% 85A(ZLCM202010Y1651NY)'   | 'ZIT'   | 'ZLCM202010Y1651NY'  | 'EU(V1)'     | ''           | 'DISCRETE' | 'DIP'   | 'IXD-BEN'       | 'ZIT_ZLCM202010Y1651NY.pdf'     | 'ZLCM202010Y1651NY.msg' | ''             | ''          | ''      | '20210330' | ''         | '' 
 '650UH'            | '85A'       | 'THLF'    | 'EMPTY'  | 'DC165^00000'(!)        = ''              | ''             | 'DC165^00000'           |'LC24-5_P20W10'| 'CHOKE 650UH 30% 85A(ZLCM202010Y1651NY)'   | 'ZIT'   | 'ZLCM202010Y1651NY'  | 'EU(V1)'     | ''           | 'DISCRETE' | 'DIP'   | 'IXD-BEN'       | 'ZIT_ZLCM202010Y1651NY.pdf'     | 'ZLCM202010Y1651NY.msg' | ''             | ''          | ''      | '20210330' | ''         | '' 
 '360UH'            | '22A'       | 'SMLF'    | 'IND'    | 'DC136M0T000'(!)        = ''              | ''             | 'DC136M0T000'           |'L_PA5141_23-5X24-3'| 'CHOKE 360UH 40% 22A(PA5141.405NLT)'       | 'PLE'   | 'PA5141.405NLT'      | 'EU(V1)'     | ''           | 'DISCRETE' | ''      | 'P07-BENJAMIN'  | 'PLE_PA5141.405NLT.pdf'         | ''                      | ''             | ''          | ''      | '20210419' | ''         | '' 
 '360UH'            | '22A'       | 'SMLF'    | 'EMPTY'  | 'DC136M0T000'(!)        = ''              | ''             | 'DC136M0T000'           |'L_PA5141_23-5X24-3'| 'CHOKE 360UH 40% 22A(PA5141.405NLT)'       | 'PLE'   | 'PA5141.405NLT'      | 'EU(V1)'     | ''           | 'DISCRETE' | ''      | 'P07-BENJAMIN'  | 'PLE_PA5141.405NLT.pdf'         | ''                      | ''             | ''          | ''      | '20210419' | ''         | '' 
 '230UH'            | '12A'       | 'SMLF'    | 'IND'    | 'DC123C0T000'(!)        = ''              | ''             | 'DC123C0T000'           |'L_PAC6006_13-5X15-5'| 'CHOKE 230UH 40% 12A(PAC6006.204NLT)'      | 'PLE'   | 'PAC6006.204NLT'     | 'EU(V1)'     | ''           | 'DISCRETE' | ''      | 'P07-BENJAMIN'  | 'PLE_PAC6006.364NLT.pdf'        | 'PAC6006.204NLT.msg'    | ''             | ''          | ''      | '20210506' | ''         | '' 
 '230UH'            | '12A'       | 'SMLF'    | 'EMPTY'  | 'DC123C0T000'(!)        = ''              | ''             | 'DC123C0T000'           |'L_PAC6006_13-5X15-5'| 'CHOKE 230UH 40% 12A(PAC6006.204NLT)'      | 'PLE'   | 'PAC6006.204NLT'     | 'EU(V1)'     | ''           | 'DISCRETE' | ''      | 'P07-BENJAMIN'  | 'PLE_PAC6006.364NLT.pdf'        | 'PAC6006.204NLT.msg'    | ''             | ''          | ''      | '20210506' | ''         | '' 
 '1300UH'           | '22A'       | 'THLF'    | 'IND'    | 'DC213M0T000'(!)        = ''              | ''             | 'DC213M0T000'           |'LC35_P28-5W10'| 'CHOKE DIP 1300UH 30% 22A(DG-C281809-132)' | 'TMP'   | 'DG-C281809-132 GP'  | 'EP(V1)'     | ''           | 'DISCRETE' | 'DIP'   | 'S7I-NICK'      | 'TMP_DG-C281809-132 GP.pdf'     | ''                      | ''             | ''          | ''      | '20221004' | ''         | '' 
 '1300UH'           | '22A'       | 'THLF'    | 'EMPTY'  | 'DC213M0T000'(!)        = ''              | ''             | 'DC213M0T000'           |'LC35_P28-5W10'| 'CHOKE DIP 1300UH 30% 22A(DG-C281809-132)' | 'TMP'   | 'DG-C281809-132 GP'  | 'EP(V1)'     | ''           | 'DISCRETE' | 'DIP'   | 'S7I-NICK'      | 'TMP_DG-C281809-132 GP.pdf'     | ''                      | ''             | ''          | ''      | '20221004' | ''         | '' 
 'DLW21SN900HQ2L'   | '280MA'     | 'SMLF'    | 'IND'    | 'CX1SN900001'(!)        = ''              | ''             | 'CX1SN900001'           |'L_DLW21HNXA'| 'EMI FILTER DLW21SN900HQ2L(90,280MA)'      | 'MUR'   | 'DLW21SN900HQ2L'     | 'EP(V1)'     | 'EP(V1)'     | 'DISCRETE' | ''      | 'S9B-DONG'      | 'MUR_DLW21SN900HQ2L.pdf'        | 'DLW21SN900HQ2L.msg'    | ''             | ''          | ''      | '20230118' | ''         | '' 
 'DLW21SN900HQ2L'   | '280MA'     | 'SMLF'    | 'EMPTY'  | 'CX1SN900001'(!)        = ''              | ''             | 'CX1SN900001'           |'L_DLW21HNXA'| 'EMI FILTER DLW21SN900HQ2L(90,280MA)'      | 'MUR'   | 'DLW21SN900HQ2L'     | 'EP(V1)'     | 'EP(V1)'     | 'DISCRETE' | ''      | 'S9B-DONG'      | 'MUR_DLW21SN900HQ2L.pdf'        | 'DLW21SN900HQ2L.msg'    | ''             | ''          | ''      | '20230118' | ''         | '' 
 '1300UH'           | '22A'       | 'THLF'    | 'IND'    | 'DC213M0TD00'(!)        = ''              | ''             | 'DC213M0TD00'           |'LC35_P28-5W10XA '| 'CHOKE DIP 1300UH 30%22A(DG-C281809-132A)' | 'TMP'   | 'DG-C281809-132A GP' | 'EP(V1)'     | ''           | 'DISCRETE' | 'DIP'   | 'S7I-NICK'      | 'TMP_DG-C281809-132A GP.pdf'    | ''                      | ''             | ''          | ''      | '20230308' | ''         | '' 
 '1300UH'           | '22A'       | 'THLF'    | 'EMPTY'  | 'DC213M0TD00'(!)        = ''              | ''             | 'DC213M0TD00'           |'LC35_P28-5W10XA '| 'CHOKE DIP 1300UH 30%22A(DG-C281809-132A)' | 'TMP'   | 'DG-C281809-132A GP' | 'EP(V1)'     | ''           | 'DISCRETE' | 'DIP'   | 'S7I-NICK'      | 'TMP_DG-C281809-132A GP.pdf'    | ''                      | ''             | ''          | ''      | '20230308' | ''         | '' 
 'DLW21HN900HQ2L'   | '220MA'     | 'SMLF'    | 'IND'    | 'CX1HN900001SEL1'(!)    = ''              | ''               | 'CX1HN900001SEL1'       |'L_DLW21HN'| 'EMI FILTER DLW21HN90(50V,220MA,90)SELASN' | 'MUR'   | 'DLW21HN900HQ2L'     | 'EP(V1)'     | 'EP(V1)'     | 'DISCRETE' | ''      | 'T2H-CF'        | 'MUR_DLW21HN900HQ2L.pdf'        | 'SEL_15QPN.xlsx'        | ''             | ''          | ''      | '20230620' | ''         | '' 
 'DLW21HN900HQ2L'   | '220MA'     | 'SMLF'    | 'EMPTY'  | 'CX1HN900001SEL1'(!)    = ''              | ''               | 'CX1HN900001SEL1'       |'L_DLW21HN'| 'EMI FILTER DLW21HN90(50V,220MA,90)SELASN' | 'MUR'   | 'DLW21HN900HQ2L'     | 'EP(V1)'     | 'EP(V1)'     | 'DISCRETE' | ''      | 'T2H-CF'        | 'MUR_DLW21HN900HQ2L.pdf'        | 'SEL_15QPN.xlsx'        | ''             | ''          | ''      | '20230620' | ''         | '' 

END_PART

END.

